FILE_TYPE = MULTI_PHYS_TABLE;

PART 'SN74LVC1G07DBVR'

{========================================================================================}
:VALUE             | PACK_TYPE | MATERIAL | PART_NUMBER    = STANDARD         | LIFECYCLE        | ENVCOMP | PART_NUMBER   | JEDEC_TYPE | CLASS | DESCRIPTION                   | HEIGHT   | COMPONENT_TYPE | LEAD_LENGTH | LPID | DAY        ;
{========================================================================================}
 'SN74LVC1G07DBVR' | 'SMLF'    | 'IC'     | 'AL1G0007024'(!) = ''               | ''               | 'YES'   | 'AL1G0007024' |'SOT23-5'| 'IC'  | 'IC(5P) SN74LVC1G07DCKR(SOP)' | '.058IN' | 'SMALLSMT'     | ''          | ''   | '20100819'
 'SN74LVC1G07DBVR' | 'SMLF'    | 'EMPTY'  | 'AL1G0007024'(!) = ''               | ''               | 'YES'   | 'AL1G0007024' |'SOT23-5'| 'IO'  | 'IC(5P) SN74LVC1G07DCKR(SOP)' | '.058IN' | 'SMALLSMT'     | ''          | ''   | '20100819'

END_PART

END.

